(kicad_pcb
	(version 20241229)
	(generator "pcbnew")
	(generator_version "9.0")
	(general
		(thickness 1.6)
		(legacy_teardrops no)
	)
	(paper "A4")
	(title_block
		(title "OCuLink to PCIe adapter")
		(date "2025-06-18")
		(rev "1.0.0")
		(company "Antmicro Ltd")
		(comment 1 "www.antmicro.com")
		(comment 9 "footprints 124-128 of 159")
	)
	(layers
		(0 "F.Cu" signal)
		(4 "In1.Cu" signal)
		(6 "In2.Cu" signal)
		(2 "B.Cu" signal)
		(9 "F.Adhes" user "F.Adhesive")
		(11 "B.Adhes" user "B.Adhesive")
		(13 "F.Paste" user)
		(15 "B.Paste" user)
		(5 "F.SilkS" user "F.Silkscreen")
		(7 "B.SilkS" user "B.Silkscreen")
		(1 "F.Mask" user)
		(3 "B.Mask" user)
		(17 "Dwgs.User" user "User.Drawings")
		(19 "Cmts.User" user "User.Comments")
		(21 "Eco1.User" user "User.Eco1")
		(23 "Eco2.User" user "User.Eco2")
		(25 "Edge.Cuts" user)
		(27 "Margin" user)
		(31 "F.CrtYd" user "F.Courtyard")
		(29 "B.CrtYd" user "B.Courtyard")
		(35 "F.Fab" user)
		(33 "B.Fab" user)
	)
	(footprint "antmicro-footprints:LED_0603_1608Metric_G"
		(layer "F.Cu")
		(at 151.5 159.71)
		(descr "LED SMD 0603 Green")
		(tags "LED SMD 0603 Green")
		(property "Reference" "D3"
			(at -0.75 1.58 0)
			(layer "F.SilkS")
			(effects
				(font
					(size 0.7 0.7)
					(thickness 0.15)
				)
				(justify left bottom)
			)
		)
		(property "Value" "LED_G_0603_LTST-C190GKT"
			(at -0.001 1.599 0)
			(layer "F.Fab")
			(effects
				(font
					(size 0.7 0.7)
					(thickness 0.15)
				)
				(justify left bottom)
			)
		)
		(property "Datasheet" "https://media.digikey.com/pdf/Data%20Sheets/Lite-On%20PDFs/LTST-C190GKT.pdf"
			(at 0 0 0)
			(layer "F.Fab")
			(hide yes)
			(effects
				(font
					(size 1.27 1.27)
					(thickness 0.15)
				)
			)
		)
		(property "Description" "LED, Green, SMD, 0603, 20 mA, 2.1 V, 569 nm"
			(at 0 0 0)
			(layer "F.Fab")
			(hide yes)
			(effects
				(font
					(size 1.27 1.27)
					(thickness 0.15)
				)
			)
		)
		(property "MPN" "LTST-C190GKT"
			(at 0 0 0)
			(unlocked yes)
			(layer "F.Fab")
			(hide yes)
			(effects
				(font
					(size 1 1)
					(thickness 0.15)
				)
			)
		)
		(property "Manufacturer" "Lite-On"
			(at 0 0 0)
			(unlocked yes)
			(layer "F.Fab")
			(hide yes)
			(effects
				(font
					(size 1 1)
					(thickness 0.15)
				)
			)
		)
		(property "Color" "Green"
			(at 0 0 0)
			(unlocked yes)
			(layer "F.Fab")
			(hide yes)
			(effects
				(font
					(size 1 1)
					(thickness 0.15)
				)
			)
		)
		(property "Author" "Antmicro"
			(at 0 0 0)
			(unlocked yes)
			(layer "F.Fab")
			(hide yes)
			(effects
				(font
					(size 1 1)
					(thickness 0.15)
				)
			)
		)
		(property "License" "Apache-2.0"
			(at 0 0 0)
			(unlocked yes)
			(layer "F.Fab")
			(hide yes)
			(effects
				(font
					(size 1 1)
					(thickness 0.15)
				)
			)
		)
		(sheetname "/Power/")
		(sheetfile "power.kicad_sch")
		(attr smd)
		(fp_line
			(start -1.18 -0.319)
			(end -1.18 0.321)
			(stroke
				(width 0.15)
				(type solid)
			)
			(layer "F.SilkS")
		)
		(fp_line
			(start -0.094672 0.001008)
			(end -0.24 0.001008)
			(stroke
				(width 0.1)
				(type solid)
			)
			(layer "F.SilkS")
		)
		(fp_line
			(start -0.094672 0.001008)
			(end 0.105328 -0.198992)
			(stroke
				(width 0.1)
				(type solid)
			)
			(layer "F.SilkS")
		)
		(fp_line
			(start -0.094672 0.201008)
			(end -0.094672 -0.198992)
			(stroke
				(width 0.1)
				(type solid)
			)
			(layer "F.SilkS")
		)
		(fp_line
			(start 0.105328 0.001008)
			(end 0.24 0.001)
			(stroke
				(width 0.1)
				(type solid)
			)
			(layer "F.SilkS")
		)
		(fp_line
			(start 0.105328 0.201008)
			(end -0.094672 0.001008)
			(stroke
				(width 0.1)
				(type solid)
			)
			(layer "F.SilkS")
		)
		(fp_line
			(start 0.105328 0.201008)
			(end 0.105328 -0.198992)
			(stroke
				(width 0.1)
				(type solid)
			)
			(layer "F.SilkS")
		)
		(fp_line
			(start 0.22 -0.35)
			(end -0.22 -0.35)
			(stroke
				(width 0.15)
				(type solid)
			)
			(layer "F.SilkS")
		)
		(fp_line
			(start 0.22 0.35)
			(end -0.22 0.35)
			(stroke
				(width 0.15)
				(type solid)
			)
			(layer "F.SilkS")
		)
		(fp_rect
			(start 1.25 0.65)
			(end -1.25 -0.65)
			(stroke
				(width 0.05)
				(type solid)
			)
			(fill no)
			(layer "F.CrtYd")
		)
		(fp_line
			(start -0.199 -0.202)
			(end -0.199 0.1)
			(stroke
				(width 0.15)
				(type solid)
			)
			(layer "F.Fab")
		)
		(fp_line
			(start -0.199 0)
			(end -0.597 0)
			(stroke
				(width 0.15)
				(type solid)
			)
			(layer "F.Fab")
		)
		(fp_line
			(start -0.199 0.2)
			(end -0.199 0.1)
			(stroke
				(width 0.15)
				(type solid)
			)
			(layer "F.Fab")
		)
		(fp_line
			(start -0.101 0)
			(end 0.201 0.2)
			(stroke
				(width 0.15)
				(type solid)
			)
			(layer "F.Fab")
		)
		(fp_line
			(start 0.201 -0.202)
			(end -0.101 0)
			(stroke
				(width 0.15)
				(type solid)
			)
			(layer "F.Fab")
		)
		(fp_line
			(start 0.201 0)
			(end 0.201 -0.202)
			(stroke
				(width 0.15)
				(type solid)
			)
			(layer "F.Fab")
		)
		(fp_line
			(start 0.201 0.2)
			(end 0.201 0)
			(stroke
				(width 0.15)
				(type solid)
			)
			(layer "F.Fab")
		)
		(fp_line
			(start 0.599 0)
			(end 0.201 0)
			(stroke
				(width 0.15)
				(type solid)
			)
			(layer "F.Fab")
		)
		(fp_rect
			(start 0.848 0.4)
			(end -0.85 -0.402)
			(stroke
				(width 0.15)
				(type solid)
			)
			(fill no)
			(layer "F.Fab")
		)
		(fp_text user "Author: Antmicro"
			(at -1.4224 4.799 0)
			(layer "F.Fab")
			(effects
				(font
					(size 0.7 0.7)
					(thickness 0.15)
				)
				(justify left bottom)
			)
		)
		(fp_text user "License: Apache-2.0"
			(at -1.4224 3.599 0)
			(layer "F.Fab")
			(effects
				(font
					(size 0.7 0.7)
					(thickness 0.15)
				)
				(justify left bottom)
			)
		)
		(fp_text user "${REFERENCE}"
			(at 0 0 0)
			(layer "F.Fab")
			(effects
				(font
					(size 0.7 0.7)
					(thickness 0.15)
				)
				(justify left bottom)
			)
		)
		(pad "1" smd roundrect
			(at -0.7 0 180)
			(size 0.8 1)
			(layers "F.Cu" "F.Mask" "F.Paste")
			(roundrect_rratio 0.2)
			(net 91 "Net-(D3-C)")
			(pinfunction "C")
			(pintype "passive")
		)
		(pad "2" smd roundrect
			(at 0.7 0 180)
			(size 0.8 1)
			(layers "F.Cu" "F.Mask" "F.Paste")
			(roundrect_rratio 0.2)
			(net 134 "+3V3")
			(pinfunction "A")
			(pintype "passive")
		)
	)
	(footprint "antmicro-footprints:MP_Pad6mm_Drill3.2mm"
		(layer "F.Cu")
		(at 104.8 34.2 -90)
		(property "Reference" "MP3"
			(at 0 0 90)
			(layer "F.SilkS")
			(hide yes)
			(effects
				(font
					(size 0.7 0.7)
					(thickness 0.15)
				)
				(justify right top)
			)
		)
		(property "Value" "MP_Pad6mm_Drill3.2mm"
			(at 0 3.899999 90)
			(layer "F.Fab")
			(effects
				(font
					(size 0.7 0.7)
					(thickness 0.15)
				)
				(justify right top)
			)
		)
		(property "Description" "Mechanical part"
			(at 0 0 90)
			(layer "F.Fab")
			(hide yes)
			(effects
				(font
					(size 1.27 1.27)
					(thickness 0.15)
				)
			)
		)
		(property "Author" "Antmicro"
			(at 0 0 270)
			(unlocked yes)
			(layer "F.Fab")
			(hide yes)
			(effects
				(font
					(size 1 1)
					(thickness 0.15)
				)
			)
		)
		(property "License" "Apache-2.0"
			(at 0 0 270)
			(unlocked yes)
			(layer "F.Fab")
			(hide yes)
			(effects
				(font
					(size 1 1)
					(thickness 0.15)
				)
			)
		)
		(sheetname "/")
		(sheetfile "oculink-to-pcie-adapter.kicad_sch")
		(attr exclude_from_pos_files exclude_from_bom)
		(fp_circle
			(center 0 0)
			(end 3.25 0)
			(stroke
				(width 0.05)
				(type default)
			)
			(fill no)
			(layer "F.CrtYd")
		)
		(fp_text user "Author: Antmicro"
			(at -0.178001 7.225 90)
			(layer "F.Fab")
			(effects
				(font
					(size 0.7 0.7)
					(thickness 0.15)
				)
				(justify right top)
			)
		)
		(fp_text user "License: Apache-2.0"
			(at -0.178 8.425001 90)
			(layer "F.Fab")
			(effects
				(font
					(size 0.7 0.7)
					(thickness 0.15)
				)
				(justify right top)
			)
		)
		(fp_text user "${REFERENCE}"
			(at 0 0 90)
			(layer "F.Fab")
			(effects
				(font
					(size 0.7 0.7)
					(thickness 0.15)
				)
				(justify right top)
			)
		)
		(pad "1" thru_hole circle
			(at 0 0 270)
			(size 6 6)
			(drill 3.2)
			(layers "*.Cu" "*.Mask")
			(remove_unused_layers no)
			(net 66 "GND")
			(pintype "passive")
		)
	)
	(footprint "antmicro-footprints:L_Abracon_ASPIAIG-Q8080"
		(layer "F.Cu")
		(at 140 100.75 180)
		(property "Reference" "L2"
			(at -2.2 -5.85 180)
			(layer "F.SilkS")
			(effects
				(font
					(size 0.7 0.7)
					(thickness 0.15)
				)
				(justify left bottom)
			)
		)
		(property "Value" "L_4u7_14.6A_Abracon-Q8080"
			(at 0 10.16 180)
			(unlocked yes)
			(layer "F.Fab")
			(effects
				(font
					(size 0.7 0.7)
					(thickness 0.15)
				)
				(justify left bottom)
			)
		)
		(property "Datasheet" "https://www.mouser.com/datasheet/2/3/ASPIAIG_Q8080-2256550.pdf"
			(at 0 0 0)
			(layer "F.Fab")
			(hide yes)
			(effects
				(font
					(size 1.27 1.27)
					(thickness 0.15)
				)
			)
		)
		(property "Description" "Power Inductors - SMD 4.7 UH 20%"
			(at 0 0 0)
			(layer "F.Fab")
			(hide yes)
			(effects
				(font
					(size 1.27 1.27)
					(thickness 0.15)
				)
			)
		)
		(property "MPN" "ASPIAIG-Q8080-4R7M-T"
			(at 0 0 180)
			(unlocked yes)
			(layer "F.Fab")
			(hide yes)
			(effects
				(font
					(size 1 1)
					(thickness 0.15)
				)
			)
		)
		(property "ISat" "17A"
			(at 0 0 180)
			(unlocked yes)
			(layer "F.Fab")
			(hide yes)
			(effects
				(font
					(size 1 1)
					(thickness 0.15)
				)
			)
		)
		(property "IMax" "14.6A"
			(at 0 0 180)
			(unlocked yes)
			(layer "F.Fab")
			(hide yes)
			(effects
				(font
					(size 1 1)
					(thickness 0.15)
				)
			)
		)
		(property "Size" "8.9x8.5"
			(at 0 0 180)
			(unlocked yes)
			(layer "F.Fab")
			(hide yes)
			(effects
				(font
					(size 1 1)
					(thickness 0.15)
				)
			)
		)
		(property "Val" "4.7u/14.6A"
			(at 0 0 180)
			(unlocked yes)
			(layer "F.Fab")
			(hide yes)
			(effects
				(font
					(size 1 1)
					(thickness 0.15)
				)
			)
		)
		(property "Author" "Antmicro"
			(at 0 0 180)
			(unlocked yes)
			(layer "F.Fab")
			(hide yes)
			(effects
				(font
					(size 1 1)
					(thickness 0.15)
				)
			)
		)
		(property "License" "Apache-2.0"
			(at 0 0 180)
			(unlocked yes)
			(layer "F.Fab")
			(hide yes)
			(effects
				(font
					(size 1 1)
					(thickness 0.15)
				)
			)
		)
		(property "Manufacturer" "Abracon"
			(at 0 0 180)
			(unlocked yes)
			(layer "F.Fab")
			(hide yes)
			(effects
				(font
					(size 1 1)
					(thickness 0.15)
				)
			)
		)
		(sheetname "/USB-PD/")
		(sheetfile "usb-pd.kicad_sch")
		(attr smd)
		(fp_rect
			(start -4.6 -4.4)
			(end 4.6 4.4)
			(stroke
				(width 0.15)
				(type default)
			)
			(fill no)
			(layer "F.SilkS")
		)
		(fp_rect
			(start -4.85 -4.64)
			(end 4.85 4.64)
			(stroke
				(width 0.05)
				(type solid)
			)
			(fill no)
			(layer "F.CrtYd")
		)
		(fp_rect
			(start -4.597 -4.394)
			(end 4.597 4.394)
			(stroke
				(width 0.15)
				(type default)
			)
			(fill no)
			(layer "F.Fab")
		)
		(fp_text user "${REFERENCE}"
			(at 0 0 180)
			(layer "F.Fab")
			(effects
				(font
					(size 0.7 0.7)
					(thickness 0.15)
				)
				(justify left bottom)
			)
		)
		(fp_text user "Author: Antmicro"
			(at -5.2 13.36 0)
			(layer "F.Fab")
			(effects
				(font
					(size 0.7 0.7)
					(thickness 0.15)
				)
				(justify right top)
			)
		)
		(fp_text user "License: Apache-2.0"
			(at -5.2 14.56 0)
			(layer "F.Fab")
			(effects
				(font
					(size 0.7 0.7)
					(thickness 0.15)
				)
				(justify right top)
			)
		)
		(pad "1" smd roundrect
			(at -2.675 0 180)
			(size 2.65 7.8)
			(layers "F.Cu" "F.Mask" "F.Paste")
			(roundrect_rratio 0.05)
			(net 143 "/USB-PD/12V_SW")
			(pintype "passive")
		)
		(pad "2" smd roundrect
			(at 2.675 0 180)
			(size 2.65 7.8)
			(layers "F.Cu" "F.Mask" "F.Paste")
			(roundrect_rratio 0.05)
			(net 187 "/USB-PD/12V_CONV")
			(pintype "passive")
		)
	)
	(footprint "antmicro-footprints:C_0805_2012Metric"
		(layer "F.Cu")
		(at 132 98.5)
		(descr "Capacitor SMD 0805")
		(tags "capacitor SMD 0805")
		(property "Reference" "C28"
			(at -4.2 0.5 180)
			(layer "F.SilkS")
			(effects
				(font
					(size 0.7 0.7)
					(thickness 0.15)
				)
				(justify left bottom)
			)
		)
		(property "Value" "C_22u_25V_0805"
			(at -2.055717 1.963153 0)
			(layer "F.Fab")
			(effects
				(font
					(size 0.7 0.7)
					(thickness 0.15)
				)
				(justify left bottom)
			)
		)
		(property "Datasheet" "https://product.samsungsem.com/mlcc/CL21A226MAYNNN.do"
			(at 0 0 0)
			(layer "F.Fab")
			(hide yes)
			(effects
				(font
					(size 1.27 1.27)
					(thickness 0.15)
				)
			)
		)
		(property "Description" "SMT Multilayer Ceramic Capacitor, 22uF, +/-20%, 25V, X5R, 0805 [2012 Metric]"
			(at 0 0 0)
			(layer "F.Fab")
			(hide yes)
			(effects
				(font
					(size 1.27 1.27)
					(thickness 0.15)
				)
			)
		)
		(property "MPN" "CL21A226MAYNNNE"
			(at 0 0 0)
			(unlocked yes)
			(layer "F.Fab")
			(hide yes)
			(effects
				(font
					(size 1 1)
					(thickness 0.15)
				)
			)
		)
		(property "Manufacturer" "Samsung Electro-Mechanics"
			(at 0 0 0)
			(unlocked yes)
			(layer "F.Fab")
			(hide yes)
			(effects
				(font
					(size 1 1)
					(thickness 0.15)
				)
			)
		)
		(property "License" "Apache-2.0"
			(at 0 0 0)
			(unlocked yes)
			(layer "F.Fab")
			(hide yes)
			(effects
				(font
					(size 1 1)
					(thickness 0.15)
				)
			)
		)
		(property "Author" "Antmicro"
			(at 0 0 0)
			(unlocked yes)
			(layer "F.Fab")
			(hide yes)
			(effects
				(font
					(size 1 1)
					(thickness 0.15)
				)
			)
		)
		(property "Val" "22u"
			(at 0 0 0)
			(unlocked yes)
			(layer "F.Fab")
			(hide yes)
			(effects
				(font
					(size 1 1)
					(thickness 0.15)
				)
			)
		)
		(property "Voltage" "25V"
			(at 0 0 0)
			(unlocked yes)
			(layer "F.Fab")
			(hide yes)
			(effects
				(font
					(size 1 1)
					(thickness 0.15)
				)
			)
		)
		(property "Dielectric" "X5R"
			(at 0 0 0)
			(unlocked yes)
			(layer "F.Fab")
			(hide yes)
			(effects
				(font
					(size 1 1)
					(thickness 0.15)
				)
			)
		)
		(property "Public" "False"
			(at 0 0 0)
			(unlocked yes)
			(layer "F.Fab")
			(hide yes)
			(effects
				(font
					(size 1 1)
					(thickness 0.15)
				)
			)
		)
		(sheetname "/USB-PD/")
		(sheetfile "usb-pd.kicad_sch")
		(attr smd)
		(fp_line
			(start -0.3 -0.7)
			(end 0.3 -0.7)
			(stroke
				(width 0.15)
				(type solid)
			)
			(layer "F.SilkS")
		)
		(fp_line
			(start -0.3 0.7)
			(end 0.3 0.7)
			(stroke
				(width 0.15)
				(type solid)
			)
			(layer "F.SilkS")
		)
		(fp_rect
			(start 1.95 -0.9)
			(end -1.95 0.9)
			(stroke
				(width 0.05)
				(type default)
			)
			(fill no)
			(layer "F.CrtYd")
		)
		(fp_rect
			(start -0.95 -0.675)
			(end 0.95 0.675)
			(stroke
				(width 0.15)
				(type solid)
			)
			(fill no)
			(layer "F.Fab")
		)
		(fp_text user "Author: Antmicro"
			(at -1.9 5.947 0)
			(layer "F.Fab")
			(effects
				(font
					(size 0.7 0.7)
					(thickness 0.15)
				)
				(justify left bottom)
			)
		)
		(fp_text user "License: Apache-2.0"
			(at -1.9 4.947 0)
			(layer "F.Fab")
			(effects
				(font
					(size 0.7 0.7)
					(thickness 0.15)
				)
				(justify left bottom)
			)
		)
		(fp_text user "${REFERENCE}"
			(at 0 0 0)
			(layer "F.Fab")
			(effects
				(font
					(size 0.7 0.7)
					(thickness 0.15)
				)
				(justify left bottom)
			)
		)
		(pad "1" smd roundrect
			(at -1.1 0)
			(size 1.2 1.3)
			(layers "F.Cu" "F.Mask" "F.Paste")
			(roundrect_rratio 0.25)
			(net 66 "GND")
			(pintype "passive")
		)
		(pad "2" smd roundrect
			(at 1.1 0)
			(size 1.2 1.3)
			(layers "F.Cu" "F.Mask" "F.Paste")
			(roundrect_rratio 0.25)
			(net 187 "/USB-PD/12V_CONV")
			(pintype "passive")
		)
	)
	(footprint "antmicro-footprints:R_0402_1005Metric"
		(layer "F.Cu")
		(at 135.7005 68.050001 90)
		(descr "Resistor SMD 0402")
		(tags "resistor SMD 0402")
		(property "Reference" "R36"
			(at 1.3 -5.45 90)
			(layer "F.SilkS")
			(effects
				(font
					(size 0.7 0.7)
					(thickness 0.15)
				)
				(justify right top)
			)
		)
		(property "Value" "R_10k_0402"
			(at -1.011843 1.772046 90)
			(layer "F.Fab")
			(effects
				(font
					(size 0.7 0.7)
					(thickness 0.15)
				)
				(justify left bottom)
			)
		)
		(property "Datasheet" "https://www.bourns.com/docs/product-datasheets/cr.pdf"
			(at 0 0 90)
			(layer "F.Fab")
			(hide yes)
			(effects
				(font
					(size 1.27 1.27)
					(thickness 0.15)
				)
			)
		)
		(property "Description" "SMD Chip Resistor, 10 kohm, ± 1%, 62.5 mW, 0402 [1005 Metric], Thick Film, General Purpose"
			(at 0 0 90)
			(layer "F.Fab")
			(hide yes)
			(effects
				(font
					(size 1.27 1.27)
					(thickness 0.15)
				)
			)
		)
		(property "MPN" "CR0402-FX-1002GLF"
			(at 0 0 90)
			(unlocked yes)
			(layer "F.Fab")
			(hide yes)
			(effects
				(font
					(size 1 1)
					(thickness 0.15)
				)
			)
		)
		(property "Manufacturer" "Bourns"
			(at 0 0 90)
			(unlocked yes)
			(layer "F.Fab")
			(hide yes)
			(effects
				(font
					(size 1 1)
					(thickness 0.15)
				)
			)
		)
		(property "License" "Apache-2.0"
			(at 0 0 90)
			(unlocked yes)
			(layer "F.Fab")
			(hide yes)
			(effects
				(font
					(size 1 1)
					(thickness 0.15)
				)
			)
		)
		(property "Author" "Antmicro"
			(at 0 0 90)
			(unlocked yes)
			(layer "F.Fab")
			(hide yes)
			(effects
				(font
					(size 1 1)
					(thickness 0.15)
				)
			)
		)
		(property "Val" "10k"
			(at 0 0 90)
			(unlocked yes)
			(layer "F.Fab")
			(hide yes)
			(effects
				(font
					(size 1 1)
					(thickness 0.15)
				)
			)
		)
		(property "Tolerance" "1%"
			(at 0 0 90)
			(unlocked yes)
			(layer "F.Fab")
			(hide yes)
			(effects
				(font
					(size 1 1)
					(thickness 0.15)
				)
			)
		)
		(sheetname "/USB-PD/")
		(sheetfile "usb-pd.kicad_sch")
		(attr smd)
		(fp_rect
			(start -0.925 -0.47)
			(end 0.925 0.47)
			(stroke
				(width 0.05)
				(type default)
			)
			(fill no)
			(layer "F.CrtYd")
		)
		(fp_rect
			(start -0.5 -0.25)
			(end 0.5 0.25)
			(stroke
				(width 0.15)
				(type solid)
			)
			(fill no)
			(layer "F.Fab")
		)
		(fp_text user "${REFERENCE}"
			(at 0 0 270)
			(layer "F.Fab")
			(effects
				(font
					(size 0.7 0.7)
					(thickness 0.15)
				)
				(justify right top)
			)
		)
		(fp_text user "Author: Antmicro"
			(at -0.95 4.169 90)
			(layer "F.Fab")
			(effects
				(font
					(size 0.7 0.7)
					(thickness 0.15)
				)
				(justify left bottom)
			)
		)
		(fp_text user "License: Apache-2.0"
			(at -0.949999 5.169 90)
			(layer "F.Fab")
			(effects
				(font
					(size 0.7 0.7)
					(thickness 0.15)
				)
				(justify left bottom)
			)
		)
		(pad "1" smd roundrect
			(at -0.48 0 90)
			(size 0.59 0.64)
			(layers "F.Cu" "F.Mask" "F.Paste")
			(roundrect_rratio 0.25)
			(net 176 "Net-(Q8-D)")
			(pintype "passive")
		)
		(pad "2" smd roundrect
			(at 0.48 0 90)
			(size 0.59 0.64)
			(layers "F.Cu" "F.Mask" "F.Paste")
			(roundrect_rratio 0.25)
			(net 167 "Net-(D4-C_{R})")
			(pintype "passive")
		)
	)
)
